# BASEBOARD_FAB2 (Tioga Pass) — schematic netlist excerpt (pin names and nets, part order shuffled) for the footprints in the layout excerpt that follows; sources: Cadence DE-HDL packaged netlist, KiCad conversion of Wiwynn_Tioga_Pass_MB.brd

C6U3  CAP  47UF 4V 20% X6S  pkg 0805  page 233 : A = PVPP_GHJ ; B = GND
C2T5  CAP_A  0.1UF 16V 10% X7R  pkg 0402V  page 185 : A = P3V3 ; B = GND
C3M10  CAP  4.7UF 6.3V 10% X6S  pkg 0603  page 232 : A = VR_VB_PVPP_DEF ; B = AGND_PVPP_DEF

(kicad_pcb
	(version 20260206)
	(generator "pcbnew")
	(generator_version "10.0")
	(general
		(thickness 1.6)
		(legacy_teardrops no)
	)
	(paper "A4")
	(title_block
		(title "Wiwynn_Tioga_Pass_MB.brd")
		(comment 1 "Tioga Pass / footprints 3273-3275 of 4770")
	)
	(layers
		(0 "F.Cu" signal "TOP")
		(4 "In1.Cu" signal "L2GND")
		(6 "In2.Cu" signal "L3")
		(8 "In3.Cu" signal "L4GND")
		(10 "In4.Cu" signal "L5")
		(12 "In5.Cu" signal "L6GND")
		(14 "In6.Cu" signal "L7VCC")
		(16 "In7.Cu" signal "L8VCC")
		(18 "In8.Cu" signal "L9GND")
		(20 "In9.Cu" signal "L10")
		(22 "In10.Cu" signal "L11GND")
		(24 "In11.Cu" signal "L12")
		(26 "In12.Cu" signal "L13GND")
		(2 "B.Cu" signal "BOTTOM")
		(9 "F.Adhes" user "F.Adhesive")
		(11 "B.Adhes" user "B.Adhesive")
		(13 "F.Paste" user "Package Geometry/Pastemask Top")
		(15 "B.Paste" user "Package Geometry/Pastemask Bottom")
		(5 "F.SilkS" user "Ref Des/Silkscreen Top")
		(7 "B.SilkS" user "Ref Des/Silkscreen Bottom")
		(1 "F.Mask" user "Board Geometry/Soldermask Top")
		(3 "B.Mask" user "Board Geometry/Soldermask Bottom")
		(17 "Dwgs.User" user "User.Drawings")
		(19 "Cmts.User" user "User.Comments")
		(21 "Eco1.User" user "User.Eco1")
		(23 "Eco2.User" user "User.Eco2")
		(25 "Edge.Cuts" user "Board Geometry/Outline")
		(27 "Margin" user)
		(31 "F.CrtYd" user "Package Geometry/Place Bound Top")
		(29 "B.CrtYd" user "Package Geometry/Place Bound Bottom")
		(35 "F.Fab" user "Ref Des/Assembly Top")
		(33 "B.Fab" user "Ref Des/Assembly Bottom")
	)
	(footprint ""
		(layer "B.Cu")
		(at 167.005 -13.208 90)
		(property "Reference" "C6U3"
			(at 0 0 90)
			(layer "B.SilkS")
			(hide yes)
			(effects
				(font
					(size 1.27 1.27)
				)
				(justify mirror)
			)
		)
		(property "Value" ""
			(at 0 0 90)
			(layer "B.Fab")
			(effects
				(font
					(size 1.27 1.27)
				)
				(justify mirror)
			)
		)
		(duplicate_pad_numbers_are_jumpers no)
		(fp_rect
			(start -0.7239 -0.2159)
			(end 0.7239 1.9939)
			(stroke
				(width 0)
				(type default)
			)
			(fill no)
			(layer "B.CrtYd")
		)
		(fp_line
			(start 0.7239 -0.2159)
			(end 0.7239 1.9939)
			(stroke
				(width 0.1)
				(type default)
			)
			(layer "B.Fab")
		)
		(fp_line
			(start -0.7239 -0.2159)
			(end 0.7239 -0.2159)
			(stroke
				(width 0.1)
				(type default)
			)
			(layer "B.Fab")
		)
		(fp_line
			(start 0.7239 1.9939)
			(end -0.7239 1.9939)
			(stroke
				(width 0.1)
				(type default)
			)
			(layer "B.Fab")
		)
		(fp_line
			(start -0.7239 1.9939)
			(end -0.7239 -0.2159)
			(stroke
				(width 0.1)
				(type default)
			)
			(layer "B.Fab")
		)
		(pad "1" smd rect
			(at 0 0 270)
			(size 1.27 1.016)
			(layers "B.Cu" "B.Mask" "B.Paste")
			(net "PVPP_GHJ")
		)
		(pad "2" smd rect
			(at 0 1.778 270)
			(size 1.27 1.016)
			(layers "B.Cu" "B.Mask" "B.Paste")
			(net "GND")
		)
		(zone
			(layer "B.Cu")
			(hatch none 0.5)
			(connect_pads
				(clearance 0)
			)
			(min_thickness 0.25)
			(keepout
				(tracks not_allowed)
				(vias allowed)
				(pads allowed)
				(copperpour not_allowed)
				(footprints allowed)
			)
			(placement
				(enabled no)
				(sheetname "")
			)
			(fill
				(thermal_gap 0.5)
				(thermal_bridge_width 0.5)
				(island_removal_mode 0)
			)
			(polygon
				(pts
					(xy 167.513 -12.573) (xy 168.275 -12.573) (xy 168.275 -13.843) (xy 167.513 -13.843)
				)
			)
		)
	)
	(footprint ""
		(layer "B.Cu")
		(at 339.3186 -131.6482)
		(property "Reference" "C3M10"
			(at 0 0 0)
			(layer "B.SilkS")
			(hide yes)
			(effects
				(font
					(size 1.27 1.27)
				)
				(justify mirror)
			)
		)
		(property "Value" ""
			(at 0 0 0)
			(layer "B.Fab")
			(effects
				(font
					(size 1.27 1.27)
				)
				(justify mirror)
			)
		)
		(duplicate_pad_numbers_are_jumpers no)
		(fp_poly
			(pts
				(xy 0.4953 -0.2032) (xy -0.4953 -0.2032) (xy -0.4953 1.6002) (xy 0.4953 1.6002)
			)
			(stroke
				(width 0)
				(type default)
			)
			(fill no)
			(layer "B.CrtYd")
		)
		(fp_line
			(start -0.4953 -0.2032)
			(end -0.4953 1.6002)
			(stroke
				(width 0.1)
				(type default)
			)
			(layer "B.Fab")
		)
		(fp_line
			(start -0.4953 1.6002)
			(end 0.4953 1.6002)
			(stroke
				(width 0.1)
				(type default)
			)
			(layer "B.Fab")
		)
		(fp_line
			(start 0.4953 -0.2032)
			(end -0.4953 -0.2032)
			(stroke
				(width 0.1)
				(type default)
			)
			(layer "B.Fab")
		)
		(fp_line
			(start 0.4953 1.6002)
			(end 0.4953 -0.2032)
			(stroke
				(width 0.1)
				(type default)
			)
			(layer "B.Fab")
		)
		(pad "1" smd rect
			(at 0 0 180)
			(size 0.762 0.889)
			(layers "B.Cu" "B.Mask" "B.Paste")
			(net "VR_VB_PVPP_DEF")
		)
		(pad "2" smd rect
			(at 0 1.397 180)
			(size 0.762 0.889)
			(layers "B.Cu" "B.Mask" "B.Paste")
			(net "AGND_PVPP_DEF")
		)
		(zone
			(layer "B.Cu")
			(hatch none 0.5)
			(connect_pads
				(clearance 0)
			)
			(min_thickness 0.25)
			(keepout
				(tracks not_allowed)
				(vias allowed)
				(pads allowed)
				(copperpour not_allowed)
				(footprints allowed)
			)
			(placement
				(enabled no)
				(sheetname "")
			)
			(fill
				(thermal_gap 0.5)
				(thermal_bridge_width 0.5)
				(island_removal_mode 0)
			)
			(polygon
				(pts
					(xy 339.6996 -131.2037) (xy 338.9376 -131.2037) (xy 338.9376 -130.6957) (xy 339.6996 -130.6957)
				)
			)
		)
	)
	(footprint ""
		(layer "B.Cu")
		(at 390.7155 -37.73551 -90)
		(property "Reference" "C2T5"
			(at 0 0 90)
			(layer "B.SilkS")
			(hide yes)
			(effects
				(font
					(size 1.27 1.27)
				)
				(justify mirror)
			)
		)
		(property "Value" ""
			(at 0 0 90)
			(layer "B.Fab")
			(effects
				(font
					(size 1.27 1.27)
				)
				(justify mirror)
			)
		)
		(duplicate_pad_numbers_are_jumpers no)
		(fp_poly
			(pts
				(xy -0.3048 -0.1016) (xy -0.3048 0.9906) (xy 0.3048 0.9906) (xy 0.3048 -0.1016)
			)
			(stroke
				(width 0)
				(type default)
			)
			(fill no)
			(layer "B.CrtYd")
		)
		(fp_line
			(start -0.3048 0.9906)
			(end -0.3048 -0.1016)
			(stroke
				(width 0.1)
				(type default)
			)
			(layer "B.Fab")
		)
		(fp_line
			(start 0.3048 0.9906)
			(end -0.3048 0.9906)
			(stroke
				(width 0.1)
				(type default)
			)
			(layer "B.Fab")
		)
		(fp_line
			(start -0.3048 -0.1016)
			(end 0.3048 -0.1016)
			(stroke
				(width 0.1)
				(type default)
			)
			(layer "B.Fab")
		)
		(fp_line
			(start 0.3048 -0.1016)
			(end 0.3048 0.9906)
			(stroke
				(width 0.1)
				(type default)
			)
			(layer "B.Fab")
		)
		(pad "1" smd rect
			(at 0 0 90)
			(size 0.508 0.508)
			(layers "B.Cu" "B.Mask" "B.Paste")
			(net "P3V3")
		)
		(pad "2" smd rect
			(at 0 0.889 90)
			(size 0.508 0.508)
			(layers "B.Cu" "B.Mask" "B.Paste")
			(net "GND")
		)
		(zone
			(layer "B.Cu")
			(hatch none 0.5)
			(connect_pads
				(clearance 0)
			)
			(min_thickness 0.25)
			(keepout
				(tracks not_allowed)
				(vias allowed)
				(pads allowed)
				(copperpour not_allowed)
				(footprints allowed)
			)
			(placement
				(enabled no)
				(sheetname "")
			)
			(fill
				(thermal_gap 0.5)
				(thermal_bridge_width 0.5)
				(island_removal_mode 0)
			)
			(polygon
				(pts
					(xy 390.0805 -37.48151) (xy 390.0805 -37.98951) (xy 390.4615 -37.98951) (xy 390.4615 -37.48151)
				)
			)
		)
		(zone
			(layer "B.Cu")
			(hatch none 0.5)
			(connect_pads
				(clearance 0)
			)
			(min_thickness 0.25)
			(keepout
				(tracks allowed)
				(vias not_allowed)
				(pads allowed)
				(copperpour not_allowed)
				(footprints allowed)
			)
			(placement
				(enabled no)
				(sheetname "")
			)
			(fill
				(thermal_gap 0.5)
				(thermal_bridge_width 0.5)
				(island_removal_mode 0)
			)
			(polygon
				(pts
					(xy 390.4615 -37.48151) (xy 390.4615 -37.98951) (xy 390.0805 -37.98951) (xy 390.0805 -37.48151)
				)
			)
		)
	)
)
